(kicad_pcb
	(version 20260206)
	(generator "pcbnew")
	(generator_version "10.0")
	(general
		(thickness 1.6)
		(legacy_teardrops no)
	)
	(paper "A4")
	(title_block
		(title "fcb — 12433-1M.1206WZS1330.brd")
		(comment 1 "Open Vault / Knox (Wiwynn) / footprints 72-78 of 495")
	)
	(layers
		(0 "F.Cu" signal "TOP")
		(4 "In1.Cu" signal "L2GND")
		(6 "In2.Cu" signal "L3VCC")
		(2 "B.Cu" signal "BOTTOM")
		(9 "F.Adhes" user "F.Adhesive")
		(11 "B.Adhes" user "B.Adhesive")
		(13 "F.Paste" user "Package Geometry/Pastemask Top")
		(15 "B.Paste" user "Package Geometry/Pastemask Bottom")
		(5 "F.SilkS" user "Ref Des/Silkscreen Top")
		(7 "B.SilkS" user "Ref Des/Silkscreen Bottom")
		(1 "F.Mask" user "Board Geometry/Soldermask Top")
		(3 "B.Mask" user "Board Geometry/Soldermask Bottom")
		(17 "Dwgs.User" user "User.Drawings")
		(19 "Cmts.User" user "User.Comments")
		(21 "Eco1.User" user "User.Eco1")
		(23 "Eco2.User" user "User.Eco2")
		(25 "Edge.Cuts" user "Board Geometry/Outline")
		(27 "Margin" user)
		(31 "F.CrtYd" user "Package Geometry/Place Bound Top")
		(29 "B.CrtYd" user "Package Geometry/Place Bound Bottom")
		(35 "F.Fab" user "Ref Des/Assembly Top")
		(33 "B.Fab" user "Ref Des/Assembly Bottom")
	)
	(footprint ""
		(layer "F.Cu")
		(at 39.243 -174.117)
		(property "Reference" "PR44"
			(at 0 0 0)
			(layer "F.SilkS")
			(hide yes)
			(effects
				(font
					(size 1.27 1.27)
				)
			)
		)
		(property "Value" "1KR2F-3-GP"
			(at 0.064008 -3.993896 0)
			(unlocked yes)
			(layer "F.Fab")
			(hide yes)
			(effects
				(font
					(size 1.016 1.016)
					(thickness 0.1524)
				)
			)
		)
		(property "Device Type" "R402H16"
			(at 0.064008 -5.517896 0)
			(unlocked yes)
			(layer "F.Fab")
			(hide yes)
			(effects
				(font
					(size 1.016 1.016)
					(thickness 0.1524)
				)
			)
		)
		(duplicate_pad_numbers_are_jumpers no)
		(fp_line
			(start -0.508 -0.9398)
			(end -0.508 0.9398)
			(stroke
				(width 0.1524)
				(type default)
			)
			(layer "F.SilkS")
		)
		(fp_line
			(start 0.508 -0.9398)
			(end -0.508 -0.9398)
			(stroke
				(width 0.1524)
				(type default)
			)
			(layer "F.SilkS")
		)
		(fp_rect
			(start -0.508 0.9398)
			(end 0.508 -0.9398)
			(stroke
				(width 0)
				(type default)
			)
			(fill no)
			(layer "F.CrtYd")
		)
		(fp_rect
			(start -0.508 0.9398)
			(end 0.508 -0.9398)
			(stroke
				(width 0)
				(type default)
			)
			(fill no)
			(layer "F.Fab")
		)
		(pad "1" smd custom
			(at 0 -0.4445)
			(size 0.1397 0.1397)
			(layers "F.Cu" "F.Mask" "F.Paste")
			(net "TEMP_ALM#")
			(options
				(clearance outline)
				(anchor circle)
			)
			(primitives
				(gr_poly
					(pts
						(arc
							(start -0.1778 -0.2794)
							(mid -0.249642 -0.249642)
							(end -0.2794 -0.1778)
						)
						(arc
							(start -0.2794 0.1778)
							(mid -0.249642 0.249642)
							(end -0.1778 0.2794)
						)
						(arc
							(start 0.1778 0.2794)
							(mid 0.249642 0.249642)
							(end 0.2794 0.1778)
						)
						(arc
							(start 0.2794 -0.1778)
							(mid 0.249642 -0.249642)
							(end 0.1778 -0.2794)
						)
					)
					(width 0)
					(fill yes)
				)
			)
		)
		(pad "2" smd custom
			(at 0 0.4445)
			(size 0.1397 0.1397)
			(layers "F.Cu" "F.Mask" "F.Paste")
			(net "TEMP_ALM#_IN")
			(options
				(clearance outline)
				(anchor circle)
			)
			(primitives
				(gr_poly
					(pts
						(arc
							(start -0.1778 -0.2794)
							(mid -0.249642 -0.249642)
							(end -0.2794 -0.1778)
						)
						(arc
							(start -0.2794 0.1778)
							(mid -0.249642 0.249642)
							(end -0.1778 0.2794)
						)
						(arc
							(start 0.1778 0.2794)
							(mid 0.249642 0.249642)
							(end 0.2794 0.1778)
						)
						(arc
							(start 0.2794 -0.1778)
							(mid 0.249642 -0.249642)
							(end 0.1778 -0.2794)
						)
					)
					(width 0)
					(fill yes)
				)
			)
		)
	)
	(footprint ""
		(layer "F.Cu")
		(at 17.91589 -175.540924 180)
		(property "Reference" "C10"
			(at 0 0 180)
			(layer "F.SilkS")
			(hide yes)
			(effects
				(font
					(size 1.27 1.27)
				)
			)
		)
		(property "Value" "SCD1U50V3KX-GP"
			(at 0 -2.8194 180)
			(unlocked yes)
			(layer "F.Fab")
			(hide yes)
			(effects
				(font
					(size 1.016 1.016)
					(thickness 0.1524)
				)
			)
		)
		(property "Device Type" "C603H36"
			(at 0 -4.3434 180)
			(unlocked yes)
			(layer "F.Fab")
			(hide yes)
			(effects
				(font
					(size 1.016 1.016)
					(thickness 0.1524)
				)
			)
		)
		(duplicate_pad_numbers_are_jumpers no)
		(fp_line
			(start 0.508 0)
			(end -0.508 0)
			(stroke
				(width 0.2032)
				(type default)
			)
			(layer "F.SilkS")
		)
		(fp_rect
			(start -0.5842 1.3335)
			(end 0.5842 -1.3335)
			(stroke
				(width 0)
				(type default)
			)
			(fill no)
			(layer "F.CrtYd")
		)
		(fp_rect
			(start -0.5842 1.3335)
			(end 0.5842 -1.3335)
			(stroke
				(width 0)
				(type default)
			)
			(fill no)
			(layer "F.Fab")
		)
		(pad "1" smd custom
			(at 0 -0.762 180)
			(size 0.2159 0.2159)
			(layers "F.Cu" "F.Mask" "F.Paste")
			(net "P3V3")
			(options
				(clearance outline)
				(anchor circle)
			)
			(primitives
				(gr_poly
					(pts
						(arc
							(start -0.3302 -0.4318)
							(mid -0.402042 -0.402042)
							(end -0.4318 -0.3302)
						)
						(arc
							(start -0.4318 0.3302)
							(mid -0.402042 0.402042)
							(end -0.3302 0.4318)
						)
						(arc
							(start 0.3302 0.4318)
							(mid 0.402042 0.402042)
							(end 0.4318 0.3302)
						)
						(arc
							(start 0.4318 -0.3302)
							(mid 0.402042 -0.402042)
							(end 0.3302 -0.4318)
						)
					)
					(width 0)
					(fill yes)
				)
			)
		)
		(pad "2" smd custom
			(at 0 0.762 180)
			(size 0.2159 0.2159)
			(layers "F.Cu" "F.Mask" "F.Paste")
			(net "GND")
			(options
				(clearance outline)
				(anchor circle)
			)
			(primitives
				(gr_poly
					(pts
						(arc
							(start -0.3302 -0.4318)
							(mid -0.402042 -0.402042)
							(end -0.4318 -0.3302)
						)
						(arc
							(start -0.4318 0.3302)
							(mid -0.402042 0.402042)
							(end -0.3302 0.4318)
						)
						(arc
							(start 0.3302 0.4318)
							(mid 0.402042 0.402042)
							(end 0.4318 0.3302)
						)
						(arc
							(start 0.4318 -0.3302)
							(mid 0.402042 -0.402042)
							(end 0.3302 -0.4318)
						)
					)
					(width 0)
					(fill yes)
				)
			)
		)
	)
	(footprint ""
		(layer "F.Cu")
		(at 39.123366 -156.22651 90)
		(property "Reference" "R6"
			(at 0 0 90)
			(layer "F.SilkS")
			(hide yes)
			(effects
				(font
					(size 1.27 1.27)
				)
			)
		)
		(property "Value" "0R2J-2-GP"
			(at 0.064008 -3.993896 90)
			(unlocked yes)
			(layer "F.Fab")
			(hide yes)
			(effects
				(font
					(size 1.016 1.016)
					(thickness 0.1524)
				)
			)
		)
		(property "Device Type" "R402H16"
			(at 0.064008 -5.517896 90)
			(unlocked yes)
			(layer "F.Fab")
			(hide yes)
			(effects
				(font
					(size 1.016 1.016)
					(thickness 0.1524)
				)
			)
		)
		(duplicate_pad_numbers_are_jumpers no)
		(fp_line
			(start 0.508 -0.9398)
			(end -0.508 -0.9398)
			(stroke
				(width 0.1524)
				(type default)
			)
			(layer "F.SilkS")
		)
		(fp_line
			(start -0.508 -0.9398)
			(end -0.508 0.9398)
			(stroke
				(width 0.1524)
				(type default)
			)
			(layer "F.SilkS")
		)
		(fp_rect
			(start -0.508 0.9398)
			(end 0.508 -0.9398)
			(stroke
				(width 0)
				(type default)
			)
			(fill no)
			(layer "F.CrtYd")
		)
		(fp_rect
			(start -0.508 0.9398)
			(end 0.508 -0.9398)
			(stroke
				(width 0)
				(type default)
			)
			(fill no)
			(layer "F.Fab")
		)
		(pad "1" smd custom
			(at 0 -0.4445 90)
			(size 0.1397 0.1397)
			(layers "F.Cu" "F.Mask" "F.Paste")
			(net "NCT7904_SMI")
			(options
				(clearance outline)
				(anchor circle)
			)
			(primitives
				(gr_poly
					(pts
						(arc
							(start -0.1778 -0.2794)
							(mid -0.249642 -0.249642)
							(end -0.2794 -0.1778)
						)
						(arc
							(start -0.2794 0.1778)
							(mid -0.249642 0.249642)
							(end -0.1778 0.2794)
						)
						(arc
							(start 0.1778 0.2794)
							(mid 0.249642 0.249642)
							(end 0.2794 0.1778)
						)
						(arc
							(start 0.2794 -0.1778)
							(mid 0.249642 -0.249642)
							(end 0.1778 -0.2794)
						)
					)
					(width 0)
					(fill yes)
				)
			)
		)
		(pad "2" smd custom
			(at 0 0.4445 90)
			(size 0.1397 0.1397)
			(layers "F.Cu" "F.Mask" "F.Paste")
			(net "TEMP_ALM#")
			(options
				(clearance outline)
				(anchor circle)
			)
			(primitives
				(gr_poly
					(pts
						(arc
							(start -0.1778 -0.2794)
							(mid -0.249642 -0.249642)
							(end -0.2794 -0.1778)
						)
						(arc
							(start -0.2794 0.1778)
							(mid -0.249642 0.249642)
							(end -0.1778 0.2794)
						)
						(arc
							(start 0.1778 0.2794)
							(mid 0.249642 0.249642)
							(end 0.2794 0.1778)
						)
						(arc
							(start 0.2794 -0.1778)
							(mid 0.249642 -0.249642)
							(end 0.1778 -0.2794)
						)
					)
					(width 0)
					(fill yes)
				)
			)
		)
	)
	(footprint ""
		(layer "F.Cu")
		(at 35.3314 -254.3556 180)
		(property "Reference" "R107"
			(at 0 0 180)
			(layer "F.SilkS")
			(hide yes)
			(effects
				(font
					(size 1.27 1.27)
				)
			)
		)
		(property "Value" "0R2J-2-GP"
			(at 0.064008 -3.993896 180)
			(unlocked yes)
			(layer "F.Fab")
			(hide yes)
			(effects
				(font
					(size 1.016 1.016)
					(thickness 0.1524)
				)
			)
		)
		(property "Device Type" "R402H16"
			(at 0.064008 -5.517896 180)
			(unlocked yes)
			(layer "F.Fab")
			(hide yes)
			(effects
				(font
					(size 1.016 1.016)
					(thickness 0.1524)
				)
			)
		)
		(duplicate_pad_numbers_are_jumpers no)
		(fp_line
			(start 0.508 -0.9398)
			(end -0.508 -0.9398)
			(stroke
				(width 0.1524)
				(type default)
			)
			(layer "F.SilkS")
		)
		(fp_line
			(start -0.508 -0.9398)
			(end -0.508 0.9398)
			(stroke
				(width 0.1524)
				(type default)
			)
			(layer "F.SilkS")
		)
		(fp_rect
			(start -0.508 0.9398)
			(end 0.508 -0.9398)
			(stroke
				(width 0)
				(type default)
			)
			(fill no)
			(layer "F.CrtYd")
		)
		(fp_rect
			(start -0.508 0.9398)
			(end 0.508 -0.9398)
			(stroke
				(width 0)
				(type default)
			)
			(fill no)
			(layer "F.Fab")
		)
		(pad "1" smd custom
			(at 0 -0.4445 180)
			(size 0.1397 0.1397)
			(layers "F.Cu" "F.Mask" "F.Paste")
			(net "I2C_C_SCL_LEDDRV")
			(options
				(clearance outline)
				(anchor circle)
			)
			(primitives
				(gr_poly
					(pts
						(arc
							(start -0.1778 -0.2794)
							(mid -0.249642 -0.249642)
							(end -0.2794 -0.1778)
						)
						(arc
							(start -0.2794 0.1778)
							(mid -0.249642 0.249642)
							(end -0.1778 0.2794)
						)
						(arc
							(start 0.1778 0.2794)
							(mid 0.249642 0.249642)
							(end 0.2794 0.1778)
						)
						(arc
							(start 0.2794 -0.1778)
							(mid 0.249642 -0.249642)
							(end 0.1778 -0.2794)
						)
					)
					(width 0)
					(fill yes)
				)
			)
		)
		(pad "2" smd custom
			(at 0 0.4445 180)
			(size 0.1397 0.1397)
			(layers "F.Cu" "F.Mask" "F.Paste")
			(net "I2C_C_SCL")
			(options
				(clearance outline)
				(anchor circle)
			)
			(primitives
				(gr_poly
					(pts
						(arc
							(start -0.1778 -0.2794)
							(mid -0.249642 -0.249642)
							(end -0.2794 -0.1778)
						)
						(arc
							(start -0.2794 0.1778)
							(mid -0.249642 0.249642)
							(end -0.1778 0.2794)
						)
						(arc
							(start 0.1778 0.2794)
							(mid 0.249642 0.249642)
							(end 0.2794 0.1778)
						)
						(arc
							(start 0.2794 -0.1778)
							(mid 0.249642 -0.249642)
							(end 0.1778 -0.2794)
						)
					)
					(width 0)
					(fill yes)
				)
			)
		)
	)
	(footprint ""
		(layer "F.Cu")
		(at 32.85109 -167.723566 180)
		(property "Reference" "R7"
			(at 0 0 180)
			(layer "F.SilkS")
			(hide yes)
			(effects
				(font
					(size 1.27 1.27)
				)
			)
		)
		(property "Value" "0R2J-2-GP"
			(at 0.064008 -3.993896 180)
			(unlocked yes)
			(layer "F.Fab")
			(hide yes)
			(effects
				(font
					(size 1.016 1.016)
					(thickness 0.1524)
				)
			)
		)
		(property "Device Type" "R402H16"
			(at 0.064008 -5.517896 180)
			(unlocked yes)
			(layer "F.Fab")
			(hide yes)
			(effects
				(font
					(size 1.016 1.016)
					(thickness 0.1524)
				)
			)
		)
		(duplicate_pad_numbers_are_jumpers no)
		(fp_line
			(start 0.508 -0.9398)
			(end -0.508 -0.9398)
			(stroke
				(width 0.1524)
				(type default)
			)
			(layer "F.SilkS")
		)
		(fp_line
			(start -0.508 -0.9398)
			(end -0.508 0.9398)
			(stroke
				(width 0.1524)
				(type default)
			)
			(layer "F.SilkS")
		)
		(fp_rect
			(start -0.508 0.9398)
			(end 0.508 -0.9398)
			(stroke
				(width 0)
				(type default)
			)
			(fill no)
			(layer "F.CrtYd")
		)
		(fp_rect
			(start -0.508 0.9398)
			(end 0.508 -0.9398)
			(stroke
				(width 0)
				(type default)
			)
			(fill no)
			(layer "F.Fab")
		)
		(pad "1" smd custom
			(at 0 -0.4445 180)
			(size 0.1397 0.1397)
			(layers "F.Cu" "F.Mask" "F.Paste")
			(net "NCT7904_RSTOUT")
			(options
				(clearance outline)
				(anchor circle)
			)
			(primitives
				(gr_poly
					(pts
						(arc
							(start -0.1778 -0.2794)
							(mid -0.249642 -0.249642)
							(end -0.2794 -0.1778)
						)
						(arc
							(start -0.2794 0.1778)
							(mid -0.249642 0.249642)
							(end -0.1778 0.2794)
						)
						(arc
							(start 0.1778 0.2794)
							(mid 0.249642 0.249642)
							(end 0.2794 0.1778)
						)
						(arc
							(start 0.2794 -0.1778)
							(mid 0.249642 -0.249642)
							(end 0.1778 -0.2794)
						)
					)
					(width 0)
					(fill yes)
				)
			)
		)
		(pad "2" smd custom
			(at 0 0.4445 180)
			(size 0.1397 0.1397)
			(layers "F.Cu" "F.Mask" "F.Paste")
			(net "TEMP_ALM#")
			(options
				(clearance outline)
				(anchor circle)
			)
			(primitives
				(gr_poly
					(pts
						(arc
							(start -0.1778 -0.2794)
							(mid -0.249642 -0.249642)
							(end -0.2794 -0.1778)
						)
						(arc
							(start -0.2794 0.1778)
							(mid -0.249642 0.249642)
							(end -0.1778 0.2794)
						)
						(arc
							(start 0.1778 0.2794)
							(mid 0.249642 0.249642)
							(end 0.2794 0.1778)
						)
						(arc
							(start 0.2794 -0.1778)
							(mid 0.249642 -0.249642)
							(end 0.1778 -0.2794)
						)
					)
					(width 0)
					(fill yes)
				)
			)
		)
	)
	(footprint ""
		(layer "F.Cu")
		(at 19.431 -111.76)
		(property "Reference" "PQ11"
			(at 0 0 0)
			(layer "F.SilkS")
			(hide yes)
			(effects
				(font
					(size 1.27 1.27)
				)
			)
		)
		(property "Value" "PH0925CL-GP"
			(at -4.2799 -0.4572 0)
			(unlocked yes)
			(layer "F.Fab")
			(hide yes)
			(effects
				(font
					(size 1.016 1.016)
					(thickness 0.1524)
				)
			)
		)
		(property "Device Type" "LFPAK-5PH48-U"
			(at -4.2799 -1.9812 0)
			(unlocked yes)
			(layer "F.Fab")
			(hide yes)
			(effects
				(font
					(size 1.016 1.016)
					(thickness 0.1524)
				)
			)
		)
		(duplicate_pad_numbers_are_jumpers no)
		(fp_line
			(start -2.7559 -6.5532)
			(end -2.7559 1.0668)
			(stroke
				(width 0.1524)
				(type default)
			)
			(layer "F.SilkS")
		)
		(fp_line
			(start -2.7559 1.0668)
			(end 2.7559 1.0668)
			(stroke
				(width 0.1524)
				(type default)
			)
			(layer "F.SilkS")
		)
		(fp_line
			(start -1.7272 1.1684)
			(end -2.1082 1.1684)
			(stroke
				(width 0.3302)
				(type default)
			)
			(layer "F.SilkS")
		)
		(fp_line
			(start 2.7559 -6.5532)
			(end -2.7559 -6.5532)
			(stroke
				(width 0.1524)
				(type default)
			)
			(layer "F.SilkS")
		)
		(fp_line
			(start 2.7559 1.0668)
			(end 2.7559 -6.5532)
			(stroke
				(width 0.1524)
				(type default)
			)
			(layer "F.SilkS")
		)
		(fp_poly
			(pts
				(xy -2.3368 1.5748) (xy -1.905 1.143) (xy -1.4732 1.5748)
			)
			(stroke
				(width 0)
				(type default)
			)
			(fill yes)
			(layer "F.SilkS")
		)
		(fp_poly
			(pts
				(xy -2.5019 -4.02971) (xy -0.3302 -4.02971) (xy -0.3302 -6.30301) (xy -2.5019 -6.30301)
			)
			(stroke
				(width 0)
				(type default)
			)
			(fill yes)
			(layer "F.Paste")
		)
		(fp_poly
			(pts
				(xy -2.5019 -1.09601) (xy -0.3302 -1.09601) (xy -0.3302 -3.36931) (xy -2.5019 -3.36931)
			)
			(stroke
				(width 0)
				(type default)
			)
			(fill yes)
			(layer "F.Paste")
		)
		(fp_poly
			(pts
				(xy 0.3302 -4.02971) (xy 2.5019 -4.02971) (xy 2.5019 -6.30301) (xy 0.3302 -6.30301)
			)
			(stroke
				(width 0)
				(type default)
			)
			(fill yes)
			(layer "F.Paste")
		)
		(fp_poly
			(pts
				(xy 0.3302 -1.09601) (xy 2.5019 -1.09601) (xy 2.5019 -3.36931) (xy 0.3302 -3.36931)
			)
			(stroke
				(width 0)
				(type default)
			)
			(fill yes)
			(layer "F.Paste")
		)
		(fp_rect
			(start -2.4511 0.3048)
			(end 2.4511 -5.6896)
			(stroke
				(width 0)
				(type default)
			)
			(fill no)
			(layer "F.CrtYd")
		)
		(fp_poly
			(pts
				(xy -3.0099 1.3208) (xy -3.0099 -6.8072) (xy 3.0099 -6.8072) (xy 3.0099 -1.016) (xy 2.4511 -1.016)
				(xy 2.4511 -5.6896) (xy -2.4511 -5.6896) (xy -2.4511 0.3048) (xy 2.4511 0.3048) (xy 2.4511 -1.0033)
				(xy 3.0099 -1.0033) (xy 3.0099 1.3208)
			)
			(stroke
				(width 0)
				(type default)
			)
			(fill no)
			(layer "F.CrtYd")
		)
		(fp_rect
			(start -3.0099 1.3208)
			(end 3.0099 -6.8072)
			(stroke
				(width 0)
				(type default)
			)
			(fill no)
			(layer "F.Fab")
		)
		(pad "1" smd rect
			(at -1.905 0)
			(size 0.762 1.6256)
			(layers "F.Cu" "F.Mask" "F.Paste")
			(net "P12VU")
		)
		(pad "2" smd rect
			(at -0.635 0)
			(size 0.762 1.6256)
			(layers "F.Cu" "F.Mask" "F.Paste")
			(net "P12VU")
		)
		(pad "3" smd rect
			(at 0.635 0)
			(size 0.762 1.6256)
			(layers "F.Cu" "F.Mask" "F.Paste")
			(net "P12VU")
		)
		(pad "4" smd rect
			(at 1.905 0)
			(size 0.762 1.6256)
			(layers "F.Cu" "F.Mask" "F.Paste")
			(net "P12VU_2490_GATE_DRV_2")
		)
		(pad "5" smd rect
			(at 0 -3.69951)
			(size 5.0038 5.207)
			(layers "F.Cu" "F.Mask" "F.Paste")
			(net "P12VU_NET")
		)
	)
	(footprint ""
		(layer "F.Cu")
		(at 6.1214 -174.7774 180)
		(property "Reference" "C53"
			(at 0 0 180)
			(layer "F.SilkS")
			(hide yes)
			(effects
				(font
					(size 1.27 1.27)
				)
			)
		)
		(property "Value" "SC1U16V3KX-5GP"
			(at 0 -2.8194 180)
			(unlocked yes)
			(layer "F.Fab")
			(hide yes)
			(effects
				(font
					(size 1.016 1.016)
					(thickness 0.1524)
				)
			)
		)
		(property "Device Type" "C603H36"
			(at 0 -4.3434 180)
			(unlocked yes)
			(layer "F.Fab")
			(hide yes)
			(effects
				(font
					(size 1.016 1.016)
					(thickness 0.1524)
				)
			)
		)
		(duplicate_pad_numbers_are_jumpers no)
		(fp_line
			(start 0.508 0)
			(end -0.508 0)
			(stroke
				(width 0.2032)
				(type default)
			)
			(layer "F.SilkS")
		)
		(fp_rect
			(start -0.5842 1.3335)
			(end 0.5842 -1.3335)
			(stroke
				(width 0)
				(type default)
			)
			(fill no)
			(layer "F.CrtYd")
		)
		(fp_rect
			(start -0.5842 1.3335)
			(end 0.5842 -1.3335)
			(stroke
				(width 0)
				(type default)
			)
			(fill no)
			(layer "F.Fab")
		)
		(pad "1" smd custom
			(at 0 -0.762 180)
			(size 0.2159 0.2159)
			(layers "F.Cu" "F.Mask" "F.Paste")
			(net "P3V3")
			(options
				(clearance outline)
				(anchor circle)
			)
			(primitives
				(gr_poly
					(pts
						(arc
							(start -0.3302 -0.4318)
							(mid -0.402042 -0.402042)
							(end -0.4318 -0.3302)
						)
						(arc
							(start -0.4318 0.3302)
							(mid -0.402042 0.402042)
							(end -0.3302 0.4318)
						)
						(arc
							(start 0.3302 0.4318)
							(mid 0.402042 0.402042)
							(end 0.4318 0.3302)
						)
						(arc
							(start 0.4318 -0.3302)
							(mid 0.402042 -0.402042)
							(end 0.3302 -0.4318)
						)
					)
					(width 0)
					(fill yes)
				)
			)
		)
		(pad "2" smd custom
			(at 0 0.762 180)
			(size 0.2159 0.2159)
			(layers "F.Cu" "F.Mask" "F.Paste")
			(net "GND")
			(options
				(clearance outline)
				(anchor circle)
			)
			(primitives
				(gr_poly
					(pts
						(arc
							(start -0.3302 -0.4318)
							(mid -0.402042 -0.402042)
							(end -0.4318 -0.3302)
						)
						(arc
							(start -0.4318 0.3302)
							(mid -0.402042 0.402042)
							(end -0.3302 0.4318)
						)
						(arc
							(start 0.3302 0.4318)
							(mid 0.402042 0.402042)
							(end 0.4318 0.3302)
						)
						(arc
							(start 0.4318 -0.3302)
							(mid 0.402042 -0.402042)
							(end 0.3302 -0.4318)
						)
					)
					(width 0)
					(fill yes)
				)
			)
		)
	)
)
